(kicad_pcb
	(version 20260206)
	(generator "pcbnew")
	(generator_version "10.0")
	(general
		(thickness 1.6)
		(legacy_teardrops no)
	)
	(paper "A4")
	(title_block
		(title "timecard-production-celestica-r4006 — R4006-B0001-02_R01.brd")
		(comment 1 "Time Appliance Project (Time Card) / footprints 624-630 of 1113")
	)
	(layers
		(0 "F.Cu" signal "TOP")
		(4 "In1.Cu" signal "L02_GND1")
		(6 "In2.Cu" signal "L03_SIG1")
		(8 "In3.Cu" signal "L04_GND2")
		(10 "In4.Cu" signal "L05_VCC1")
		(12 "In5.Cu" signal "L06_VCC2")
		(14 "In6.Cu" signal "L07_GND3")
		(16 "In7.Cu" signal "L08_SIG2")
		(18 "In8.Cu" signal "L09_GND4")
		(2 "B.Cu" signal "BOTTOM")
		(9 "F.Adhes" user "F.Adhesive")
		(11 "B.Adhes" user "B.Adhesive")
		(13 "F.Paste" user "Package Geometry/Pastemask Top")
		(15 "B.Paste" user "Package Geometry/Pastemask Bottom")
		(5 "F.SilkS" user "Ref Des/Silkscreen Top")
		(7 "B.SilkS" user "Ref Des/Silkscreen Bottom")
		(1 "F.Mask" user "Board Geometry/Soldermask Top")
		(3 "B.Mask" user "Board Geometry/Soldermask Bottom")
		(17 "Dwgs.User" user "User.Drawings")
		(19 "Cmts.User" user "User.Comments")
		(21 "Eco1.User" user "User.Eco1")
		(23 "Eco2.User" user "User.Eco2")
		(25 "Edge.Cuts" user "Board Geometry/Outline")
		(27 "Margin" user)
		(31 "F.CrtYd" user "Package Geometry/Place Bound Top")
		(29 "B.CrtYd" user "Package Geometry/Place Bound Bottom")
		(35 "F.Fab" user "Ref Des/Assembly Top")
		(33 "B.Fab" user "Ref Des/Assembly Bottom")
	)
	(footprint ""
		(layer "F.Cu")
		(at 42.164 -133.223)
		(property "Reference" "SP21"
			(at 0 0 0)
			(layer "F.SilkS")
			(hide yes)
			(effects
				(font
					(size 1.27 1.27)
				)
			)
		)
		(property "Value" ""
			(at 0 0 0)
			(layer "F.Fab")
			(effects
				(font
					(size 1.27 1.27)
				)
			)
		)
		(duplicate_pad_numbers_are_jumpers no)
	)
	(footprint ""
		(layer "F.Cu")
		(at 92.837 -70.993 90)
		(property "Reference" "TP55"
			(at 0.8636 -0.34925 90)
			(unlocked yes)
			(layer "F.SilkS")
			(effects
				(font
					(size 0.635 0.4064)
					(thickness 0.1524)
				)
				(justify left)
			)
		)
		(property "Value" ""
			(at 0 0 90)
			(layer "F.Fab")
			(effects
				(font
					(size 1.27 1.27)
				)
			)
		)
		(property "Device Type" "TP_PIONT-TP010CT020B030_PTH-TPA"
			(at -1.341882 0.996696 90)
			(unlocked yes)
			(layer "F.Fab")
			(hide yes)
			(effects
				(font
					(size 0.7874 0.5842)
					(thickness 0.1524)
				)
				(justify left)
			)
		)
		(duplicate_pad_numbers_are_jumpers no)
		(fp_poly
			(pts
				(arc
					(start 0 0.889)
					(mid 0 -0.889)
					(end 0 0.889)
				)
			)
			(stroke
				(width 0)
				(type default)
			)
			(fill no)
			(layer "B.CrtYd")
		)
		(fp_poly
			(pts
				(arc
					(start 0 0.889)
					(mid 0 -0.889)
					(end 0 0.889)
				)
			)
			(stroke
				(width 0)
				(type default)
			)
			(fill no)
			(layer "F.CrtYd")
		)
		(pad "1" thru_hole circle
			(at 0 0 90)
			(size 0.508 0.508)
			(drill 0.254)
			(layers "*.Cu" "*.Mask")
			(remove_unused_layers no)
			(net "XP1R2V_FPGA")
			(clearance 0.1016)
			(padstack
				(mode front_inner_back)
				(layer "Inner"
					(shape circle)
					(size 0.508 0.508)
					(clearance 0.1016)
				)
				(layer "B.Cu"
					(shape circle)
					(size 0.762 0.762)
					(clearance -0.0254)
				)
			)
		)
	)
	(footprint ""
		(layer "F.Cu")
		(at 88.392 -93.599 90)
		(property "Reference" "C20"
			(at -3.81 -5.80263 90)
			(unlocked yes)
			(layer "F.SilkS")
			(effects
				(font
					(size 0.7874 0.5842)
					(thickness 0.1524)
				)
			)
		)
		(property "Value" "VAL*"
			(at 0.0762 3.134106 90)
			(unlocked yes)
			(layer "F.Fab")
			(hide yes)
			(effects
				(font
					(size 0.7874 0.5842)
					(thickness 0.1524)
				)
			)
		)
		(property "Tolerance" "TOL*"
			(at 0.0762 4.048506 90)
			(unlocked yes)
			(layer "Cmts.User")
			(hide yes)
			(effects
				(font
					(size 0.7874 0.5842)
					(thickness 0.1524)
				)
			)
		)
		(property "User Part Number" "PARTNUM*"
			(at 0.1016 5.013706 90)
			(unlocked yes)
			(layer "Cmts.User")
			(hide yes)
			(effects
				(font
					(size 0.7874 0.5842)
					(thickness 0.1524)
				)
			)
		)
		(property "Device Type" "CAPACITOR-G107-0F226-CM,22UF,2A"
			(at 0.0508 2.194306 90)
			(unlocked yes)
			(layer "F.Fab")
			(hide yes)
			(effects
				(font
					(size 0.7874 0.5842)
					(thickness 0.1524)
				)
			)
		)
		(duplicate_pad_numbers_are_jumpers no)
		(fp_line
			(start 1.5748 -0.9398)
			(end -1.5748 -0.9398)
			(stroke
				(width 0.1)
				(type default)
			)
			(layer "F.SilkS")
		)
		(fp_line
			(start -1.5748 -0.9398)
			(end -1.5748 0.9398)
			(stroke
				(width 0.1)
				(type default)
			)
			(layer "F.SilkS")
		)
		(fp_line
			(start 1.5748 0.9398)
			(end 1.5748 -0.9398)
			(stroke
				(width 0.1)
				(type default)
			)
			(layer "F.SilkS")
		)
		(fp_line
			(start -1.5748 0.9398)
			(end 1.5748 0.9398)
			(stroke
				(width 0.1)
				(type default)
			)
			(layer "F.SilkS")
		)
		(fp_rect
			(start 1.5748 0.9398)
			(end -1.5748 -0.9398)
			(stroke
				(width 0)
				(type default)
			)
			(fill no)
			(layer "F.CrtYd")
		)
		(fp_line
			(start 1.016 -0.635)
			(end -1.016 -0.635)
			(stroke
				(width 0.1)
				(type default)
			)
			(layer "F.Fab")
		)
		(fp_line
			(start -1.016 -0.635)
			(end -1.016 0.635)
			(stroke
				(width 0.1)
				(type default)
			)
			(layer "F.Fab")
		)
		(fp_line
			(start 1.016 0.635)
			(end 1.016 -0.635)
			(stroke
				(width 0.1)
				(type default)
			)
			(layer "F.Fab")
		)
		(fp_line
			(start -1.016 0.635)
			(end 1.016 0.635)
			(stroke
				(width 0.1)
				(type default)
			)
			(layer "F.Fab")
		)
		(pad "1" smd rect
			(at -0.8382 0 90)
			(size 0.9652 1.3716)
			(layers "F.Cu" "F.Mask" "F.Paste")
			(net "XP3R3V")
		)
		(pad "2" smd rect
			(at 0.8382 0 90)
			(size 0.9652 1.3716)
			(layers "F.Cu" "F.Mask" "F.Paste")
			(net "SG")
		)
		(zone
			(layer "F.Cu")
			(hatch none 0.5)
			(connect_pads
				(clearance 0)
			)
			(min_thickness 0.25)
			(keepout
				(tracks allowed)
				(vias not_allowed)
				(pads allowed)
				(copperpour not_allowed)
				(footprints allowed)
			)
			(placement
				(enabled no)
				(sheetname "")
			)
			(fill
				(thermal_gap 0.5)
				(thermal_bridge_width 0.5)
				(island_removal_mode 0)
			)
			(polygon
				(pts
					(xy 89.027 -93.8276) (xy 87.757 -93.8276) (xy 87.757 -93.3704) (xy 89.027 -93.3704)
				)
			)
		)
	)
	(footprint ""
		(layer "F.Cu")
		(at 101.4476 -82.2706)
		(property "Reference" "R462"
			(at -2.6416 0.77597 0)
			(unlocked yes)
			(layer "F.SilkS")
			(effects
				(font
					(size 0.7874 0.5842)
					(thickness 0.1524)
				)
			)
		)
		(property "Value" "VAL*"
			(at 0.02032 2.13233 0)
			(unlocked yes)
			(layer "F.Fab")
			(hide yes)
			(effects
				(font
					(size 0.7874 0.5842)
					(thickness 0.1524)
				)
			)
		)
		(property "Tolerance" "TOL*"
			(at 0.044704 3.05435 0)
			(unlocked yes)
			(layer "Cmts.User")
			(hide yes)
			(effects
				(font
					(size 0.7874 0.5842)
					(thickness 0.1524)
				)
			)
		)
		(property "User Part Number" "PARTNUM*"
			(at 0.02032 4.024884 0)
			(unlocked yes)
			(layer "Cmts.User")
			(hide yes)
			(effects
				(font
					(size 0.7874 0.5842)
					(thickness 0.1524)
				)
			)
		)
		(property "Device Type" "RESISTOR-G155-133R0-01,33OHM,1%"
			(at 0.008382 1.210564 0)
			(unlocked yes)
			(layer "F.Fab")
			(hide yes)
			(effects
				(font
					(size 0.7874 0.5842)
					(thickness 0.1524)
				)
			)
		)
		(duplicate_pad_numbers_are_jumpers no)
		(fp_line
			(start -1.143 -0.5588)
			(end -1.143 0.5588)
			(stroke
				(width 0.1)
				(type default)
			)
			(layer "F.SilkS")
		)
		(fp_line
			(start -1.143 0.5588)
			(end 1.143 0.5588)
			(stroke
				(width 0.1)
				(type default)
			)
			(layer "F.SilkS")
		)
		(fp_line
			(start 1.143 -0.5588)
			(end -1.143 -0.5588)
			(stroke
				(width 0.1)
				(type default)
			)
			(layer "F.SilkS")
		)
		(fp_line
			(start 1.143 0.5588)
			(end 1.143 -0.5588)
			(stroke
				(width 0.1)
				(type default)
			)
			(layer "F.SilkS")
		)
		(fp_poly
			(pts
				(xy -1.143 0.5588) (xy 1.143 0.5588) (xy 1.143 -0.5588) (xy -1.143 -0.5588)
			)
			(stroke
				(width 0)
				(type default)
			)
			(fill no)
			(layer "F.CrtYd")
		)
		(fp_line
			(start -0.508 -0.3048)
			(end -0.508 0.3048)
			(stroke
				(width 0.1)
				(type default)
			)
			(layer "F.Fab")
		)
		(fp_line
			(start -0.508 0.3048)
			(end 0.508 0.3048)
			(stroke
				(width 0.1)
				(type default)
			)
			(layer "F.Fab")
		)
		(fp_line
			(start 0.508 -0.3048)
			(end -0.508 -0.3048)
			(stroke
				(width 0.1)
				(type default)
			)
			(layer "F.Fab")
		)
		(fp_line
			(start 0.508 0.3048)
			(end 0.508 -0.3048)
			(stroke
				(width 0.1)
				(type default)
			)
			(layer "F.Fab")
		)
		(pad "1" smd rect
			(at -0.5334 0)
			(size 0.7112 0.6096)
			(layers "F.Cu" "F.Mask" "F.Paste")
			(net "FT4232_MUX2_SEL")
		)
		(pad "2" smd rect
			(at 0.5334 0)
			(size 0.7112 0.6096)
			(layers "F.Cu" "F.Mask" "F.Paste")
			(net "MUX2_SEL")
		)
		(zone
			(layer "F.Cu")
			(hatch none 0.5)
			(connect_pads
				(clearance 0)
			)
			(min_thickness 0.25)
			(keepout
				(tracks allowed)
				(vias not_allowed)
				(pads allowed)
				(copperpour not_allowed)
				(footprints allowed)
			)
			(placement
				(enabled no)
				(sheetname "")
			)
			(fill
				(thermal_gap 0.5)
				(thermal_bridge_width 0.5)
				(island_removal_mode 0)
			)
			(polygon
				(pts
					(xy 101.3714 -81.9658) (xy 101.5238 -81.9658) (xy 101.5238 -82.5754) (xy 101.3714 -82.5754)
				)
			)
		)
		(zone
			(layer "F.Cu")
			(hatch none 0.5)
			(connect_pads
				(clearance 0)
			)
			(min_thickness 0.25)
			(keepout
				(tracks not_allowed)
				(vias allowed)
				(pads allowed)
				(copperpour not_allowed)
				(footprints allowed)
			)
			(placement
				(enabled no)
				(sheetname "")
			)
			(fill
				(thermal_gap 0.5)
				(thermal_bridge_width 0.5)
				(island_removal_mode 0)
			)
			(polygon
				(pts
					(xy 101.3714 -81.9658) (xy 101.5238 -81.9658) (xy 101.5238 -82.5754) (xy 101.3714 -82.5754)
				)
			)
		)
	)
	(footprint ""
		(layer "F.Cu")
		(at 120.346978 -39.323264 90)
		(property "Reference" "TP132"
			(at 0 0 90)
			(layer "F.SilkS")
			(hide yes)
			(effects
				(font
					(size 1.27 1.27)
				)
			)
		)
		(property "Value" ""
			(at 0 0 90)
			(layer "F.Fab")
			(effects
				(font
					(size 1.27 1.27)
				)
			)
		)
		(property "Device Type" "TP_PIONT-TP010CT020B030_PTH-TPA"
			(at -1.341882 0.996696 90)
			(unlocked yes)
			(layer "F.Fab")
			(hide yes)
			(effects
				(font
					(size 0.7874 0.5842)
					(thickness 0.1524)
				)
				(justify left)
			)
		)
		(duplicate_pad_numbers_are_jumpers no)
		(fp_poly
			(pts
				(arc
					(start 0 0.889)
					(mid 0 -0.889)
					(end 0 0.889)
				)
			)
			(stroke
				(width 0)
				(type default)
			)
			(fill no)
			(layer "B.CrtYd")
		)
		(fp_poly
			(pts
				(arc
					(start 0 0.889)
					(mid 0 -0.889)
					(end 0 0.889)
				)
			)
			(stroke
				(width 0)
				(type default)
			)
			(fill no)
			(layer "F.CrtYd")
		)
		(pad "1" thru_hole circle
			(at 0 0 90)
			(size 0.508 0.508)
			(drill 0.254)
			(layers "*.Cu" "*.Mask")
			(remove_unused_layers no)
			(net "IO_L20P_34")
			(clearance 0.1016)
			(padstack
				(mode front_inner_back)
				(layer "Inner"
					(shape circle)
					(size 0.508 0.508)
					(clearance 0.1016)
				)
				(layer "B.Cu"
					(shape circle)
					(size 0.762 0.762)
					(clearance -0.0254)
				)
			)
		)
	)
	(footprint ""
		(layer "F.Cu")
		(at 42.9514 -97.5614)
		(property "Reference" "C41"
			(at 0.635 4.58597 0)
			(unlocked yes)
			(layer "F.SilkS")
			(effects
				(font
					(size 0.7874 0.5842)
					(thickness 0.1524)
				)
			)
		)
		(property "Value" "VAL*"
			(at 0.0762 2.067306 0)
			(unlocked yes)
			(layer "F.Fab")
			(hide yes)
			(effects
				(font
					(size 0.7874 0.5842)
					(thickness 0.1524)
				)
			)
		)
		(property "Device Type" "CAPACITOR-G105-0B104-EK,0.1UF,A"
			(at 0.0508 1.127506 0)
			(unlocked yes)
			(layer "F.Fab")
			(hide yes)
			(effects
				(font
					(size 0.7874 0.5842)
					(thickness 0.1524)
				)
			)
		)
		(property "User Part Number" "PARTNUM*"
			(at 0.1016 4.023106 0)
			(unlocked yes)
			(layer "Cmts.User")
			(hide yes)
			(effects
				(font
					(size 0.7874 0.5842)
					(thickness 0.1524)
				)
			)
		)
		(property "Tolerance" "TOL*"
			(at 0.0762 3.032506 0)
			(unlocked yes)
			(layer "Cmts.User")
			(hide yes)
			(effects
				(font
					(size 0.7874 0.5842)
					(thickness 0.1524)
				)
			)
		)
		(duplicate_pad_numbers_are_jumpers no)
		(fp_line
			(start -1.143 -0.5588)
			(end -1.143 0.5588)
			(stroke
				(width 0.1)
				(type default)
			)
			(layer "F.SilkS")
		)
		(fp_line
			(start -1.143 0.5588)
			(end 1.143 0.5588)
			(stroke
				(width 0.1)
				(type default)
			)
			(layer "F.SilkS")
		)
		(fp_line
			(start 1.143 -0.5588)
			(end -1.143 -0.5588)
			(stroke
				(width 0.1)
				(type default)
			)
			(layer "F.SilkS")
		)
		(fp_line
			(start 1.143 0.5588)
			(end 1.143 -0.5588)
			(stroke
				(width 0.1)
				(type default)
			)
			(layer "F.SilkS")
		)
		(fp_rect
			(start 1.143 -0.5588)
			(end -1.143 0.5588)
			(stroke
				(width 0)
				(type default)
			)
			(fill no)
			(layer "F.CrtYd")
		)
		(fp_line
			(start -0.508 -0.3048)
			(end -0.508 0.3048)
			(stroke
				(width 0.1)
				(type default)
			)
			(layer "F.Fab")
		)
		(fp_line
			(start -0.508 0.3048)
			(end 0.508 0.3048)
			(stroke
				(width 0.1)
				(type default)
			)
			(layer "F.Fab")
		)
		(fp_line
			(start 0.508 -0.3048)
			(end -0.508 -0.3048)
			(stroke
				(width 0.1)
				(type default)
			)
			(layer "F.Fab")
		)
		(fp_line
			(start 0.508 0.3048)
			(end 0.508 -0.3048)
			(stroke
				(width 0.1)
				(type default)
			)
			(layer "F.Fab")
		)
		(pad "1" smd rect
			(at -0.5334 0)
			(size 0.7112 0.6096)
			(layers "F.Cu" "F.Mask" "F.Paste")
			(net "VIN_XP5R0V")
		)
		(pad "2" smd rect
			(at 0.5334 0)
			(size 0.7112 0.6096)
			(layers "F.Cu" "F.Mask" "F.Paste")
			(net "SG")
		)
		(zone
			(layer "F.Cu")
			(hatch none 0.5)
			(connect_pads
				(clearance 0)
			)
			(min_thickness 0.25)
			(keepout
				(tracks allowed)
				(vias not_allowed)
				(pads allowed)
				(copperpour not_allowed)
				(footprints allowed)
			)
			(placement
				(enabled no)
				(sheetname "")
			)
			(fill
				(thermal_gap 0.5)
				(thermal_bridge_width 0.5)
				(island_removal_mode 0)
			)
			(polygon
				(pts
					(xy 43.0276 -97.8662) (xy 42.8752 -97.8662) (xy 42.8752 -97.2566) (xy 43.0276 -97.2566)
				)
			)
		)
	)
	(footprint ""
		(layer "F.Cu")
		(at 98.044 -64.2874 -90)
		(property "Reference" "R283"
			(at 2.6924 -0.80137 90)
			(unlocked yes)
			(layer "F.SilkS")
			(effects
				(font
					(size 0.7874 0.5842)
					(thickness 0.1524)
				)
			)
		)
		(property "Value" "VAL*"
			(at 0.02032 2.13233 270)
			(unlocked yes)
			(layer "F.Fab")
			(hide yes)
			(effects
				(font
					(size 0.7874 0.5842)
					(thickness 0.1524)
				)
			)
		)
		(property "Tolerance" "TOL*"
			(at 0.044704 3.05435 270)
			(unlocked yes)
			(layer "Cmts.User")
			(hide yes)
			(effects
				(font
					(size 0.7874 0.5842)
					(thickness 0.1524)
				)
			)
		)
		(property "User Part Number" "PARTNUM*"
			(at 0.02032 4.024884 270)
			(unlocked yes)
			(layer "Cmts.User")
			(hide yes)
			(effects
				(font
					(size 0.7874 0.5842)
					(thickness 0.1524)
				)
			)
		)
		(property "Device Type" "RESISTOR-G155-11002-01,10KOHM,A"
			(at 0.008382 1.210564 270)
			(unlocked yes)
			(layer "F.Fab")
			(hide yes)
			(effects
				(font
					(size 0.7874 0.5842)
					(thickness 0.1524)
				)
			)
		)
		(duplicate_pad_numbers_are_jumpers no)
		(fp_line
			(start -1.143 0.5588)
			(end 1.143 0.5588)
			(stroke
				(width 0.1)
				(type default)
			)
			(layer "F.SilkS")
		)
		(fp_line
			(start 1.143 0.5588)
			(end 1.143 -0.5588)
			(stroke
				(width 0.1)
				(type default)
			)
			(layer "F.SilkS")
		)
		(fp_line
			(start -1.143 -0.5588)
			(end -1.143 0.5588)
			(stroke
				(width 0.1)
				(type default)
			)
			(layer "F.SilkS")
		)
		(fp_line
			(start 1.143 -0.5588)
			(end -1.143 -0.5588)
			(stroke
				(width 0.1)
				(type default)
			)
			(layer "F.SilkS")
		)
		(fp_poly
			(pts
				(xy -1.143 0.5588) (xy 1.143 0.5588) (xy 1.143 -0.5588) (xy -1.143 -0.5588)
			)
			(stroke
				(width 0)
				(type default)
			)
			(fill no)
			(layer "F.CrtYd")
		)
		(fp_line
			(start -0.508 0.3048)
			(end 0.508 0.3048)
			(stroke
				(width 0.1)
				(type default)
			)
			(layer "F.Fab")
		)
		(fp_line
			(start 0.508 0.3048)
			(end 0.508 -0.3048)
			(stroke
				(width 0.1)
				(type default)
			)
			(layer "F.Fab")
		)
		(fp_line
			(start -0.508 -0.3048)
			(end -0.508 0.3048)
			(stroke
				(width 0.1)
				(type default)
			)
			(layer "F.Fab")
		)
		(fp_line
			(start 0.508 -0.3048)
			(end -0.508 -0.3048)
			(stroke
				(width 0.1)
				(type default)
			)
			(layer "F.Fab")
		)
		(pad "1" smd rect
			(at -0.5334 0 270)
			(size 0.7112 0.6096)
			(layers "F.Cu" "F.Mask" "F.Paste")
			(net "XP3R3V_FPGA")
		)
		(pad "2" smd rect
			(at 0.5334 0 270)
			(size 0.7112 0.6096)
			(layers "F.Cu" "F.Mask" "F.Paste")
			(net "FPGA_IO_2")
		)
		(zone
			(layer "F.Cu")
			(hatch none 0.5)
			(connect_pads
				(clearance 0)
			)
			(min_thickness 0.25)
			(keepout
				(tracks allowed)
				(vias not_allowed)
				(pads allowed)
				(copperpour not_allowed)
				(footprints allowed)
			)
			(placement
				(enabled no)
				(sheetname "")
			)
			(fill
				(thermal_gap 0.5)
				(thermal_bridge_width 0.5)
				(island_removal_mode 0)
			)
			(polygon
				(pts
					(xy 97.7392 -64.3636) (xy 97.7392 -64.2112) (xy 98.3488 -64.2112) (xy 98.3488 -64.3636)
				)
			)
		)
		(zone
			(layer "F.Cu")
			(hatch none 0.5)
			(connect_pads
				(clearance 0)
			)
			(min_thickness 0.25)
			(keepout
				(tracks not_allowed)
				(vias allowed)
				(pads allowed)
				(copperpour not_allowed)
				(footprints allowed)
			)
			(placement
				(enabled no)
				(sheetname "")
			)
			(fill
				(thermal_gap 0.5)
				(thermal_bridge_width 0.5)
				(island_removal_mode 0)
			)
			(polygon
				(pts
					(xy 97.7392 -64.3636) (xy 97.7392 -64.2112) (xy 98.3488 -64.2112) (xy 98.3488 -64.3636)
				)
			)
		)
	)
)
